(kicad_pcb
	(version 20260206)
	(generator "pcbnew")
	(generator_version "10.0")
	(general
		(thickness 1.6)
		(legacy_teardrops no)
	)
	(paper "A4")
	(title_block
		(title "pdpb — Lightning_PDPB_BRD.brd")
		(comment 1 "Lightning (Wiwynn / Facebook NVMe JBOF) / footprints 387-393 of 1140")
	)
	(layers
		(0 "F.Cu" signal "TOP")
		(4 "In1.Cu" signal "L2GND")
		(6 "In2.Cu" signal "L3")
		(8 "In3.Cu" signal "L4VCC")
		(10 "In4.Cu" signal "L5VCC")
		(12 "In5.Cu" signal "L6")
		(14 "In6.Cu" signal "L7GND")
		(2 "B.Cu" signal "BOTTOM")
		(9 "F.Adhes" user "F.Adhesive")
		(11 "B.Adhes" user "B.Adhesive")
		(13 "F.Paste" user "Package Geometry/Pastemask Top")
		(15 "B.Paste" user "Package Geometry/Pastemask Bottom")
		(5 "F.SilkS" user "Ref Des/Silkscreen Top")
		(7 "B.SilkS" user "Ref Des/Silkscreen Bottom")
		(1 "F.Mask" user "Board Geometry/Soldermask Top")
		(3 "B.Mask" user "Board Geometry/Soldermask Bottom")
		(17 "Dwgs.User" user "User.Drawings")
		(19 "Cmts.User" user "User.Comments")
		(21 "Eco1.User" user "User.Eco1")
		(23 "Eco2.User" user "User.Eco2")
		(25 "Edge.Cuts" user "Board Geometry/Outline")
		(27 "Margin" user)
		(31 "F.CrtYd" user "Package Geometry/Place Bound Top")
		(29 "B.CrtYd" user "Package Geometry/Place Bound Bottom")
		(35 "F.Fab" user "Ref Des/Assembly Top")
		(33 "B.Fab" user "Ref Des/Assembly Bottom")
	)
	(footprint ""
		(layer "F.Cu")
		(at 25.7048 -410.6418 90)
		(property "Reference" "R9844"
			(at 0 0 90)
			(layer "F.SilkS")
			(hide yes)
			(effects
				(font
					(size 1.27 1.27)
				)
			)
		)
		(property "Value" "2K2R5F-GP"
			(at 0 -8.9535 90)
			(unlocked yes)
			(layer "F.Fab")
			(hide yes)
			(effects
				(font
					(size 1.27 1.016)
					(thickness 0.1524)
				)
			)
		)
		(property "Device Type" "R805H24"
			(at 0 -10.6299 90)
			(unlocked yes)
			(layer "F.Fab")
			(hide yes)
			(effects
				(font
					(size 1.27 1.016)
					(thickness 0.1524)
				)
			)
		)
		(duplicate_pad_numbers_are_jumpers no)
		(fp_line
			(start 0.889 -1.7018)
			(end -0.889 -1.7018)
			(stroke
				(width 0.1524)
				(type default)
			)
			(layer "F.SilkS")
		)
		(fp_line
			(start 0.889 -1.7018)
			(end 0.889 -0.381)
			(stroke
				(width 0.1524)
				(type default)
			)
			(layer "F.SilkS")
		)
		(fp_line
			(start -0.889 -1.7018)
			(end -0.889 0.2794)
			(stroke
				(width 0.1524)
				(type default)
			)
			(layer "F.SilkS")
		)
		(fp_line
			(start -0.889 0.0762)
			(end -0.889 1.7018)
			(stroke
				(width 0.1524)
				(type default)
			)
			(layer "F.SilkS")
		)
		(fp_line
			(start 0.889 1.7018)
			(end 0.889 -0.508)
			(stroke
				(width 0.1524)
				(type default)
			)
			(layer "F.SilkS")
		)
		(fp_line
			(start -0.889 1.7018)
			(end 0.889 1.7018)
			(stroke
				(width 0.1524)
				(type default)
			)
			(layer "F.SilkS")
		)
		(fp_poly
			(pts
				(xy 0.9652 -1.778) (xy 0.9652 1.778) (xy -0.9652 1.778) (xy -0.9652 -1.778)
			)
			(stroke
				(width 0)
				(type default)
			)
			(fill no)
			(layer "F.CrtYd")
		)
		(fp_rect
			(start -0.9652 1.778)
			(end 0.9652 -1.778)
			(stroke
				(width 0)
				(type default)
			)
			(fill no)
			(layer "F.Fab")
		)
		(pad "1" smd rect
			(at 0 -0.9652 90)
			(size 1.397 1.143)
			(layers "F.Cu" "F.Mask" "F.Paste")
			(net "P12V_SSD10")
		)
		(pad "2" smd rect
			(at 0 0.9652 90)
			(size 1.397 1.143)
			(layers "F.Cu" "F.Mask" "F.Paste")
			(net "P12V_MOST10_GATE_D")
		)
	)
	(footprint ""
		(layer "F.Cu")
		(at 39.116 -411.734)
		(property "Reference" "R9751"
			(at 0 0 0)
			(layer "F.SilkS")
			(hide yes)
			(effects
				(font
					(size 1.27 1.27)
				)
			)
		)
		(property "Value" "4K7R2J-2-GP"
			(at 0.064008 -3.993896 0)
			(unlocked yes)
			(layer "F.Fab")
			(hide yes)
			(effects
				(font
					(size 1.016 1.016)
					(thickness 0.1524)
				)
			)
		)
		(property "Device Type" "R402H16"
			(at 0.064008 -5.517896 0)
			(unlocked yes)
			(layer "F.Fab")
			(hide yes)
			(effects
				(font
					(size 1.016 1.016)
					(thickness 0.1524)
				)
			)
		)
		(duplicate_pad_numbers_are_jumpers no)
		(fp_line
			(start -0.508 -0.9398)
			(end -0.508 0.9398)
			(stroke
				(width 0.1524)
				(type default)
			)
			(layer "F.SilkS")
		)
		(fp_line
			(start 0.508 -0.9398)
			(end -0.508 -0.9398)
			(stroke
				(width 0.1524)
				(type default)
			)
			(layer "F.SilkS")
		)
		(fp_rect
			(start -0.508 0.9398)
			(end 0.508 -0.9398)
			(stroke
				(width 0)
				(type default)
			)
			(fill no)
			(layer "F.CrtYd")
		)
		(fp_rect
			(start -0.508 0.9398)
			(end 0.508 -0.9398)
			(stroke
				(width 0)
				(type default)
			)
			(fill no)
			(layer "F.Fab")
		)
		(pad "1" smd custom
			(at 0 -0.4445)
			(size 0.1397 0.1397)
			(layers "F.Cu" "F.Mask" "F.Paste")
			(net "P3V3")
			(options
				(clearance outline)
				(anchor circle)
			)
			(primitives
				(gr_poly
					(pts
						(arc
							(start -0.1778 -0.2794)
							(mid -0.249642 -0.249642)
							(end -0.2794 -0.1778)
						)
						(arc
							(start -0.2794 0.1778)
							(mid -0.249642 0.249642)
							(end -0.1778 0.2794)
						)
						(arc
							(start 0.1778 0.2794)
							(mid 0.249642 0.249642)
							(end 0.2794 0.1778)
						)
						(arc
							(start 0.2794 -0.1778)
							(mid 0.249642 -0.249642)
							(end 0.1778 -0.2794)
						)
					)
					(width 0)
					(fill yes)
				)
			)
		)
		(pad "2" smd custom
			(at 0 0.4445)
			(size 0.1397 0.1397)
			(layers "F.Cu" "F.Mask" "F.Paste")
			(net "SSD10_PWREN")
			(options
				(clearance outline)
				(anchor circle)
			)
			(primitives
				(gr_poly
					(pts
						(arc
							(start -0.1778 -0.2794)
							(mid -0.249642 -0.249642)
							(end -0.2794 -0.1778)
						)
						(arc
							(start -0.2794 0.1778)
							(mid -0.249642 0.249642)
							(end -0.1778 0.2794)
						)
						(arc
							(start 0.1778 0.2794)
							(mid 0.249642 0.249642)
							(end 0.2794 0.1778)
						)
						(arc
							(start 0.2794 -0.1778)
							(mid 0.249642 -0.249642)
							(end 0.1778 -0.2794)
						)
					)
					(width 0)
					(fill yes)
				)
			)
		)
	)
	(footprint ""
		(layer "F.Cu")
		(at 37.1856 -35.052)
		(property "Reference" "R9842"
			(at 0 0 0)
			(layer "F.SilkS")
			(hide yes)
			(effects
				(font
					(size 1.27 1.27)
				)
			)
		)
		(property "Value" "0R2J-2-GP"
			(at 0.064008 -3.993896 0)
			(unlocked yes)
			(layer "F.Fab")
			(hide yes)
			(effects
				(font
					(size 1.016 1.016)
					(thickness 0.1524)
				)
			)
		)
		(property "Device Type" "R402H16"
			(at 0.064008 -5.517896 0)
			(unlocked yes)
			(layer "F.Fab")
			(hide yes)
			(effects
				(font
					(size 1.016 1.016)
					(thickness 0.1524)
				)
			)
		)
		(duplicate_pad_numbers_are_jumpers no)
		(fp_line
			(start -0.508 -0.9398)
			(end -0.508 0.9398)
			(stroke
				(width 0.1524)
				(type default)
			)
			(layer "F.SilkS")
		)
		(fp_line
			(start 0.508 -0.9398)
			(end -0.508 -0.9398)
			(stroke
				(width 0.1524)
				(type default)
			)
			(layer "F.SilkS")
		)
		(fp_rect
			(start -0.508 0.9398)
			(end 0.508 -0.9398)
			(stroke
				(width 0)
				(type default)
			)
			(fill no)
			(layer "F.CrtYd")
		)
		(fp_rect
			(start -0.508 0.9398)
			(end 0.508 -0.9398)
			(stroke
				(width 0)
				(type default)
			)
			(fill no)
			(layer "F.Fab")
		)
		(pad "1" smd custom
			(at 0 -0.4445)
			(size 0.1397 0.1397)
			(layers "F.Cu" "F.Mask" "F.Paste")
			(net "ATTN_LED_DR9_R")
			(options
				(clearance outline)
				(anchor circle)
			)
			(primitives
				(gr_poly
					(pts
						(arc
							(start -0.1778 -0.2794)
							(mid -0.249642 -0.249642)
							(end -0.2794 -0.1778)
						)
						(arc
							(start -0.2794 0.1778)
							(mid -0.249642 0.249642)
							(end -0.1778 0.2794)
						)
						(arc
							(start 0.1778 0.2794)
							(mid 0.249642 0.249642)
							(end 0.2794 0.1778)
						)
						(arc
							(start 0.2794 -0.1778)
							(mid 0.249642 -0.249642)
							(end 0.1778 -0.2794)
						)
					)
					(width 0)
					(fill yes)
				)
			)
		)
		(pad "2" smd custom
			(at 0 0.4445)
			(size 0.1397 0.1397)
			(layers "F.Cu" "F.Mask" "F.Paste")
			(net "ATTN_LED_DR9_N")
			(options
				(clearance outline)
				(anchor circle)
			)
			(primitives
				(gr_poly
					(pts
						(arc
							(start -0.1778 -0.2794)
							(mid -0.249642 -0.249642)
							(end -0.2794 -0.1778)
						)
						(arc
							(start -0.2794 0.1778)
							(mid -0.249642 0.249642)
							(end -0.1778 0.2794)
						)
						(arc
							(start 0.1778 0.2794)
							(mid 0.249642 0.249642)
							(end 0.2794 0.1778)
						)
						(arc
							(start 0.2794 -0.1778)
							(mid 0.249642 -0.249642)
							(end 0.1778 -0.2794)
						)
					)
					(width 0)
					(fill yes)
				)
			)
		)
	)
	(footprint ""
		(layer "F.Cu")
		(at 108.966 -308.229)
		(property "Reference" "R9451"
			(at 0 0 0)
			(layer "F.SilkS")
			(hide yes)
			(effects
				(font
					(size 1.27 1.27)
				)
			)
		)
		(property "Value" "4K7R2J-2-GP"
			(at 0.064008 -3.993896 0)
			(unlocked yes)
			(layer "F.Fab")
			(hide yes)
			(effects
				(font
					(size 1.016 1.016)
					(thickness 0.1524)
				)
			)
		)
		(property "Device Type" "R402H16"
			(at 0.064008 -5.517896 0)
			(unlocked yes)
			(layer "F.Fab")
			(hide yes)
			(effects
				(font
					(size 1.016 1.016)
					(thickness 0.1524)
				)
			)
		)
		(duplicate_pad_numbers_are_jumpers no)
		(fp_line
			(start -0.508 -0.9398)
			(end -0.508 0.9398)
			(stroke
				(width 0.1524)
				(type default)
			)
			(layer "F.SilkS")
		)
		(fp_line
			(start 0.508 -0.9398)
			(end -0.508 -0.9398)
			(stroke
				(width 0.1524)
				(type default)
			)
			(layer "F.SilkS")
		)
		(fp_rect
			(start -0.508 0.9398)
			(end 0.508 -0.9398)
			(stroke
				(width 0)
				(type default)
			)
			(fill no)
			(layer "F.CrtYd")
		)
		(fp_rect
			(start -0.508 0.9398)
			(end 0.508 -0.9398)
			(stroke
				(width 0)
				(type default)
			)
			(fill no)
			(layer "F.Fab")
		)
		(pad "1" smd custom
			(at 0 -0.4445)
			(size 0.1397 0.1397)
			(layers "F.Cu" "F.Mask" "F.Paste")
			(net "P3V3")
			(options
				(clearance outline)
				(anchor circle)
			)
			(primitives
				(gr_poly
					(pts
						(arc
							(start -0.1778 -0.2794)
							(mid -0.249642 -0.249642)
							(end -0.2794 -0.1778)
						)
						(arc
							(start -0.2794 0.1778)
							(mid -0.249642 0.249642)
							(end -0.1778 0.2794)
						)
						(arc
							(start 0.1778 0.2794)
							(mid 0.249642 0.249642)
							(end 0.2794 0.1778)
						)
						(arc
							(start 0.2794 -0.1778)
							(mid 0.249642 -0.249642)
							(end 0.1778 -0.2794)
						)
					)
					(width 0)
					(fill yes)
				)
			)
		)
		(pad "2" smd custom
			(at 0 0.4445)
			(size 0.1397 0.1397)
			(layers "F.Cu" "F.Mask" "F.Paste")
			(net "SSD_PRSNT_NET1")
			(options
				(clearance outline)
				(anchor circle)
			)
			(primitives
				(gr_poly
					(pts
						(arc
							(start -0.1778 -0.2794)
							(mid -0.249642 -0.249642)
							(end -0.2794 -0.1778)
						)
						(arc
							(start -0.2794 0.1778)
							(mid -0.249642 0.249642)
							(end -0.1778 0.2794)
						)
						(arc
							(start 0.1778 0.2794)
							(mid 0.249642 0.249642)
							(end 0.2794 0.1778)
						)
						(arc
							(start 0.2794 -0.1778)
							(mid 0.249642 -0.249642)
							(end 0.1778 -0.2794)
						)
					)
					(width 0)
					(fill yes)
				)
			)
		)
	)
	(footprint ""
		(layer "F.Cu")
		(at 19.5834 -469.3666)
		(property "Reference" "SR1141"
			(at 0 0 0)
			(layer "F.SilkS")
			(hide yes)
			(effects
				(font
					(size 1.27 1.27)
				)
			)
		)
		(property "Value" "4K7R2F-GP"
			(at 0.064008 -3.993896 0)
			(unlocked yes)
			(layer "F.Fab")
			(hide yes)
			(effects
				(font
					(size 1.016 1.016)
					(thickness 0.1524)
				)
			)
		)
		(property "Device Type" "R402H16"
			(at 0.064008 -5.517896 0)
			(unlocked yes)
			(layer "F.Fab")
			(hide yes)
			(effects
				(font
					(size 1.016 1.016)
					(thickness 0.1524)
				)
			)
		)
		(duplicate_pad_numbers_are_jumpers no)
		(fp_line
			(start -0.508 -0.9398)
			(end -0.508 0.9398)
			(stroke
				(width 0.1524)
				(type default)
			)
			(layer "F.SilkS")
		)
		(fp_line
			(start 0.508 -0.9398)
			(end -0.508 -0.9398)
			(stroke
				(width 0.1524)
				(type default)
			)
			(layer "F.SilkS")
		)
		(fp_rect
			(start -0.508 0.9398)
			(end 0.508 -0.9398)
			(stroke
				(width 0)
				(type default)
			)
			(fill no)
			(layer "F.CrtYd")
		)
		(fp_rect
			(start -0.508 0.9398)
			(end 0.508 -0.9398)
			(stroke
				(width 0)
				(type default)
			)
			(fill no)
			(layer "F.Fab")
		)
		(pad "1" smd custom
			(at 0 -0.4445)
			(size 0.1397 0.1397)
			(layers "F.Cu" "F.Mask" "F.Paste")
			(net "P3V3")
			(options
				(clearance outline)
				(anchor circle)
			)
			(primitives
				(gr_poly
					(pts
						(arc
							(start -0.1778 -0.2794)
							(mid -0.249642 -0.249642)
							(end -0.2794 -0.1778)
						)
						(arc
							(start -0.2794 0.1778)
							(mid -0.249642 0.249642)
							(end -0.1778 0.2794)
						)
						(arc
							(start 0.1778 0.2794)
							(mid 0.249642 0.249642)
							(end 0.2794 0.1778)
						)
						(arc
							(start 0.2794 -0.1778)
							(mid 0.249642 -0.249642)
							(end 0.1778 -0.2794)
						)
					)
					(width 0)
					(fill yes)
				)
			)
		)
		(pad "2" smd custom
			(at 0 0.4445)
			(size 0.1397 0.1397)
			(layers "F.Cu" "F.Mask" "F.Paste")
			(net "SSD10_CLK0_OE_MOS_N")
			(options
				(clearance outline)
				(anchor circle)
			)
			(primitives
				(gr_poly
					(pts
						(arc
							(start -0.1778 -0.2794)
							(mid -0.249642 -0.249642)
							(end -0.2794 -0.1778)
						)
						(arc
							(start -0.2794 0.1778)
							(mid -0.249642 0.249642)
							(end -0.1778 0.2794)
						)
						(arc
							(start 0.1778 0.2794)
							(mid 0.249642 0.249642)
							(end 0.2794 0.1778)
						)
						(arc
							(start 0.2794 -0.1778)
							(mid 0.249642 -0.249642)
							(end 0.1778 -0.2794)
						)
					)
					(width 0)
					(fill yes)
				)
			)
		)
	)
	(footprint ""
		(layer "F.Cu")
		(at 201.381106 -491.110778)
		(property "Reference" "C382"
			(at 0 0 0)
			(layer "F.SilkS")
			(hide yes)
			(effects
				(font
					(size 1.27 1.27)
				)
			)
		)
		(property "Value" "SCD1U25V2KX-2-GP"
			(at 1.1811 -2.7051 0)
			(unlocked yes)
			(layer "F.Fab")
			(hide yes)
			(effects
				(font
					(size 1.016 1.016)
					(thickness 0.1524)
				)
			)
		)
		(property "Device Type" "C402H22"
			(at 1.1811 -4.2291 0)
			(unlocked yes)
			(layer "F.Fab")
			(hide yes)
			(effects
				(font
					(size 1.016 1.016)
					(thickness 0.1524)
				)
			)
		)
		(duplicate_pad_numbers_are_jumpers no)
		(fp_rect
			(start -0.4318 0.9525)
			(end 0.4318 -0.9525)
			(stroke
				(width 0)
				(type default)
			)
			(fill no)
			(layer "F.CrtYd")
		)
		(fp_rect
			(start -0.4318 0.9525)
			(end 0.4318 -0.9525)
			(stroke
				(width 0)
				(type default)
			)
			(fill no)
			(layer "F.Fab")
		)
		(pad "1" smd custom
			(at 0 -0.4445)
			(size 0.1524 0.1524)
			(layers "F.Cu" "F.Mask" "F.Paste")
			(net "P12V")
			(options
				(clearance outline)
				(anchor circle)
			)
			(primitives
				(gr_poly
					(pts
						(arc
							(start 0.3048 -0.2032)
							(mid 0.275042 -0.275042)
							(end 0.2032 -0.3048)
						)
						(arc
							(start -0.2032 -0.3048)
							(mid -0.275042 -0.275042)
							(end -0.3048 -0.2032)
						)
						(arc
							(start -0.3048 0.2032)
							(mid -0.275042 0.275042)
							(end -0.2032 0.3048)
						)
						(arc
							(start 0.2032 0.3048)
							(mid 0.275042 0.275042)
							(end 0.3048 0.2032)
						)
					)
					(width 0)
					(fill yes)
				)
			)
		)
		(pad "2" smd custom
			(at 0 0.4445)
			(size 0.1524 0.1524)
			(layers "F.Cu" "F.Mask" "F.Paste")
			(net "SW_SSD0_N")
			(options
				(clearance outline)
				(anchor circle)
			)
			(primitives
				(gr_poly
					(pts
						(arc
							(start 0.3048 -0.2032)
							(mid 0.275042 -0.275042)
							(end 0.2032 -0.3048)
						)
						(arc
							(start -0.2032 -0.3048)
							(mid -0.275042 -0.275042)
							(end -0.3048 -0.2032)
						)
						(arc
							(start -0.3048 0.2032)
							(mid -0.275042 0.275042)
							(end -0.2032 0.3048)
						)
						(arc
							(start 0.2032 0.3048)
							(mid 0.275042 0.275042)
							(end 0.3048 0.2032)
						)
					)
					(width 0)
					(fill yes)
				)
			)
		)
	)
	(footprint ""
		(layer "F.Cu")
		(at 39.243 -137.922 180)
		(property "Reference" "R9920"
			(at 0 0 180)
			(layer "F.SilkS")
			(hide yes)
			(effects
				(font
					(size 1.27 1.27)
				)
			)
		)
		(property "Value" "47KR2J-2-GP"
			(at 0.064008 -3.993896 180)
			(unlocked yes)
			(layer "F.Fab")
			(hide yes)
			(effects
				(font
					(size 1.016 1.016)
					(thickness 0.1524)
				)
			)
		)
		(property "Device Type" "R402H16"
			(at 0.064008 -5.517896 180)
			(unlocked yes)
			(layer "F.Fab")
			(hide yes)
			(effects
				(font
					(size 1.016 1.016)
					(thickness 0.1524)
				)
			)
		)
		(duplicate_pad_numbers_are_jumpers no)
		(fp_line
			(start 0.508 -0.9398)
			(end -0.508 -0.9398)
			(stroke
				(width 0.1524)
				(type default)
			)
			(layer "F.SilkS")
		)
		(fp_line
			(start -0.508 -0.9398)
			(end -0.508 0.9398)
			(stroke
				(width 0.1524)
				(type default)
			)
			(layer "F.SilkS")
		)
		(fp_rect
			(start -0.508 0.9398)
			(end 0.508 -0.9398)
			(stroke
				(width 0)
				(type default)
			)
			(fill no)
			(layer "F.CrtYd")
		)
		(fp_rect
			(start -0.508 0.9398)
			(end 0.508 -0.9398)
			(stroke
				(width 0)
				(type default)
			)
			(fill no)
			(layer "F.Fab")
		)
		(pad "1" smd custom
			(at 0 -0.4445 180)
			(size 0.1397 0.1397)
			(layers "F.Cu" "F.Mask" "F.Paste")
			(net "P3V3")
			(options
				(clearance outline)
				(anchor circle)
			)
			(primitives
				(gr_poly
					(pts
						(arc
							(start -0.1778 -0.2794)
							(mid -0.249642 -0.249642)
							(end -0.2794 -0.1778)
						)
						(arc
							(start -0.2794 0.1778)
							(mid -0.249642 0.249642)
							(end -0.1778 0.2794)
						)
						(arc
							(start 0.1778 0.2794)
							(mid 0.249642 0.249642)
							(end 0.2794 0.1778)
						)
						(arc
							(start 0.2794 -0.1778)
							(mid 0.249642 -0.249642)
							(end 0.1778 -0.2794)
						)
					)
					(width 0)
					(fill yes)
				)
			)
		)
		(pad "2" smd custom
			(at 0 0.4445 180)
			(size 0.1397 0.1397)
			(layers "F.Cu" "F.Mask" "F.Paste")
			(net "ATTN_LED_DR8_N")
			(options
				(clearance outline)
				(anchor circle)
			)
			(primitives
				(gr_poly
					(pts
						(arc
							(start -0.1778 -0.2794)
							(mid -0.249642 -0.249642)
							(end -0.2794 -0.1778)
						)
						(arc
							(start -0.2794 0.1778)
							(mid -0.249642 0.249642)
							(end -0.1778 0.2794)
						)
						(arc
							(start 0.1778 0.2794)
							(mid 0.249642 0.249642)
							(end 0.2794 0.1778)
						)
						(arc
							(start 0.2794 -0.1778)
							(mid 0.249642 -0.249642)
							(end 0.1778 -0.2794)
						)
					)
					(width 0)
					(fill yes)
				)
			)
		)
	)
)
